(kicad_pcb
	(version 20241229)
	(generator "pcbnew")
	(generator_version "9.0")
	(general
		(thickness 1.59)
		(legacy_teardrops no)
	)
	(paper "A3")
	(title_block
		(title "usb-c-power-adapter")
		(date "2025-06-24")
		(rev "1.1.2")
		(company "Antmicro")
		(comment 9 "footprints 89-92 of 122")
	)
	(layers
		(0 "F.Cu" signal)
		(4 "In1.Cu" signal)
		(6 "In2.Cu" signal)
		(2 "B.Cu" signal)
		(9 "F.Adhes" user "F.Adhesive")
		(11 "B.Adhes" user "B.Adhesive")
		(13 "F.Paste" user)
		(15 "B.Paste" user)
		(5 "F.SilkS" user "F.Silkscreen")
		(7 "B.SilkS" user "B.Silkscreen")
		(1 "F.Mask" user)
		(3 "B.Mask" user)
		(17 "Dwgs.User" user "User.Drawings")
		(19 "Cmts.User" user "User.Comments")
		(21 "Eco1.User" user "User.Eco1")
		(23 "Eco2.User" user "User.Eco2")
		(25 "Edge.Cuts" user)
		(27 "Margin" user)
		(31 "F.CrtYd" user "F.Courtyard")
		(29 "B.CrtYd" user "B.Courtyard")
		(35 "F.Fab" user)
		(33 "B.Fab" user)
	)
	(footprint "antmicro-footprints:C_0402_1005Metric"
		(layer "B.Cu")
		(at 82.476 92.35 -90)
		(descr "Capacitor SMD 0402")
		(tags "capacitor SMD 0402")
		(property "Reference" "C40"
			(at 0.5 -2.6 180)
			(layer "B.SilkS")
			(effects
				(font
					(size 0.7 0.7)
					(thickness 0.15)
				)
				(justify left bottom mirror)
			)
		)
		(property "Value" "C_1u_25V_0402"
			(at -1.022927 -2.155213 90)
			(layer "B.Fab")
			(effects
				(font
					(size 0.7 0.7)
					(thickness 0.15)
				)
				(justify left bottom mirror)
			)
		)
		(property "Datasheet" "https://www.murata.com/products/productdetail?partno=GRM155R61E105KE11%23"
			(at 0 0 270)
			(layer "F.Fab")
			(hide yes)
			(effects
				(font
					(size 1.27 1.27)
					(thickness 0.15)
				)
			)
		)
		(property "Description" "SMD Multilayer Ceramic Capacitor, 1 µF, 25 V, 0402 [1005 Metric], ± 10%, X5R, GRM Series"
			(at 0 0 270)
			(layer "F.Fab")
			(hide yes)
			(effects
				(font
					(size 1.27 1.27)
					(thickness 0.15)
				)
			)
		)
		(property "MPN" "GRM155R61E105KE11J"
			(at 0 0 270)
			(unlocked yes)
			(layer "B.Fab")
			(hide yes)
			(effects
				(font
					(size 1 1)
					(thickness 0.15)
				)
				(justify mirror)
			)
		)
		(property "Manufacturer" "Murata"
			(at 0 0 270)
			(unlocked yes)
			(layer "B.Fab")
			(hide yes)
			(effects
				(font
					(size 1 1)
					(thickness 0.15)
				)
				(justify mirror)
			)
		)
		(property "License" "Apache-2.0"
			(at 0 0 270)
			(unlocked yes)
			(layer "B.Fab")
			(hide yes)
			(effects
				(font
					(size 1 1)
					(thickness 0.15)
				)
				(justify mirror)
			)
		)
		(property "Author" "Antmicro"
			(at 0 0 270)
			(unlocked yes)
			(layer "B.Fab")
			(hide yes)
			(effects
				(font
					(size 1 1)
					(thickness 0.15)
				)
				(justify mirror)
			)
		)
		(property "Val" "1u"
			(at 0 0 270)
			(unlocked yes)
			(layer "B.Fab")
			(hide yes)
			(effects
				(font
					(size 1 1)
					(thickness 0.15)
				)
				(justify mirror)
			)
		)
		(property "Voltage" "25V"
			(at 0 0 270)
			(unlocked yes)
			(layer "B.Fab")
			(hide yes)
			(effects
				(font
					(size 1 1)
					(thickness 0.15)
				)
				(justify mirror)
			)
		)
		(property "Dielectric" "X5R"
			(at 0 0 270)
			(unlocked yes)
			(layer "B.Fab")
			(hide yes)
			(effects
				(font
					(size 1 1)
					(thickness 0.15)
				)
				(justify mirror)
			)
		)
		(sheetname "/DC-DC Converters/")
		(sheetfile "dc-dc_converters.kicad_sch")
		(attr smd)
		(fp_rect
			(start -0.925 0.47)
			(end 0.925 -0.47)
			(stroke
				(width 0.05)
				(type default)
			)
			(fill no)
			(layer "B.CrtYd")
		)
		(fp_line
			(start -0.494 0.25)
			(end -0.494 -0.248)
			(stroke
				(width 0.15)
				(type solid)
			)
			(layer "B.Fab")
		)
		(fp_line
			(start 0.504 0.25)
			(end -0.494 0.25)
			(stroke
				(width 0.15)
				(type solid)
			)
			(layer "B.Fab")
		)
		(fp_line
			(start -0.494 -0.248)
			(end 0.504 -0.248)
			(stroke
				(width 0.15)
				(type solid)
			)
			(layer "B.Fab")
		)
		(fp_line
			(start 0.504 -0.248)
			(end 0.504 0.25)
			(stroke
				(width 0.15)
				(type solid)
			)
			(layer "B.Fab")
		)
		(pad "1" smd roundrect
			(at -0.48 0 270)
			(size 0.59 0.64)
			(layers "B.Cu" "B.Mask" "B.Paste")
			(roundrect_rratio 0.25)
			(net 2 "GND")
			(pintype "passive")
		)
		(pad "2" smd roundrect
			(at 0.48 0 270)
			(size 0.59 0.64)
			(layers "B.Cu" "B.Mask" "B.Paste")
			(roundrect_rratio 0.25)
			(net 26 "Net-(D5-C)")
			(pintype "passive")
		)
	)
	(footprint "antmicro-footprints:USB-C_Receptacle_GCT_USB4105-GF-A"
		(locked yes)
		(layer "B.Cu")
		(at 87.929 61.074)
		(property "Reference" "J1"
			(at -5.252 3.95 90)
			(layer "B.SilkS")
			(effects
				(font
					(size 0.7 0.7)
					(thickness 0.15)
				)
				(justify right bottom mirror)
			)
		)
		(property "Value" "USB-C_GCT_USB4105-GF-A"
			(at 0 -5 0)
			(layer "B.Fab")
			(effects
				(font
					(size 0.7 0.7)
					(thickness 0.15)
				)
				(justify right bottom mirror)
			)
		)
		(property "Datasheet" "https://gct.co/files/drawings/usb4105.pdf"
			(at 0 0 0)
			(layer "F.Fab")
			(hide yes)
			(effects
				(font
					(size 1.27 1.27)
					(thickness 0.15)
				)
			)
		)
		(property "Description" "USB-C (USB TYPE-C) USB 2.0 Receptacle Connector 24 (16+8 Dummy) Position Surface Mount, Right Angle"
			(at 0 0 0)
			(layer "F.Fab")
			(hide yes)
			(effects
				(font
					(size 1.27 1.27)
					(thickness 0.15)
				)
			)
		)
		(property "Manufacturer" "GCT"
			(at 0 0 0)
			(unlocked yes)
			(layer "B.Fab")
			(hide yes)
			(effects
				(font
					(size 1 1)
					(thickness 0.15)
				)
				(justify mirror)
			)
		)
		(property "MPN" "USB4105-GF-A"
			(at 0 0 0)
			(unlocked yes)
			(layer "B.Fab")
			(hide yes)
			(effects
				(font
					(size 1 1)
					(thickness 0.15)
				)
				(justify mirror)
			)
		)
		(property "Author" "Antmicro"
			(at 0 0 0)
			(unlocked yes)
			(layer "B.Fab")
			(hide yes)
			(effects
				(font
					(size 1 1)
					(thickness 0.15)
				)
				(justify mirror)
			)
		)
		(property "License" "Apache-2.0"
			(at 0 0 0)
			(unlocked yes)
			(layer "B.Fab")
			(hide yes)
			(effects
				(font
					(size 1 1)
					(thickness 0.15)
				)
				(justify mirror)
			)
		)
		(sheetname "/USB PD/")
		(sheetfile "usb_pd.kicad_sch")
		(attr smd)
		(fp_line
			(start -4.79 -3.854)
			(end -4.79 -2.575)
			(stroke
				(width 0.15)
				(type solid)
			)
			(layer "B.SilkS")
		)
		(fp_line
			(start -4.79 0.145)
			(end -4.79 1.395)
			(stroke
				(width 0.15)
				(type solid)
			)
			(layer "B.SilkS")
		)
		(fp_line
			(start 4.788 -3.854)
			(end -4.79 -3.854)
			(stroke
				(width 0.15)
				(type solid)
			)
			(layer "B.SilkS")
		)
		(fp_line
			(start 4.788 -2.575)
			(end 4.788 -3.854)
			(stroke
				(width 0.15)
				(type solid)
			)
			(layer "B.SilkS")
		)
		(fp_line
			(start 4.788 0.145)
			(end 4.788 1.395)
			(stroke
				(width 0.15)
				(type solid)
			)
			(layer "B.SilkS")
		)
		(fp_circle
			(center -3.8 4.27071)
			(end -3.75 4.22071)
			(stroke
				(width 0.15)
				(type solid)
			)
			(fill yes)
			(layer "B.SilkS")
		)
		(fp_rect
			(start -5.1 4.4)
			(end 5.1 -3.9)
			(stroke
				(width 0.05)
				(type solid)
			)
			(fill no)
			(layer "B.CrtYd")
		)
		(fp_line
			(start -4.79 -3.854)
			(end 4.788 -3.854)
			(stroke
				(width 0.15)
				(type solid)
			)
			(layer "B.Fab")
		)
		(fp_line
			(start -4.79 3.676)
			(end -4.79 -3.854)
			(stroke
				(width 0.15)
				(type solid)
			)
			(layer "B.Fab")
		)
		(fp_line
			(start 4.788 -3.854)
			(end -4.702 -3.854)
			(stroke
				(width 0.15)
				(type solid)
			)
			(layer "B.Fab")
		)
		(fp_line
			(start 4.788 -3.854)
			(end 4.788 3.676)
			(stroke
				(width 0.15)
				(type solid)
			)
			(layer "B.Fab")
		)
		(fp_line
			(start 4.788 3.676)
			(end -4.79 3.676)
			(stroke
				(width 0.15)
				(type solid)
			)
			(layer "B.Fab")
		)
		(pad "" np_thru_hole circle
			(at -2.891 2.426)
			(size 0.65 0.65)
			(drill 0.65)
			(layers "*.Cu" "*.Mask")
		)
		(pad "" np_thru_hole circle
			(at 2.89 2.426)
			(size 0.65 0.65)
			(drill 0.65)
			(layers "*.Cu" "*.Mask")
		)
		(pad "A1" smd roundrect
			(at -3.202 3.5)
			(size 0.6 1.15)
			(layers "B.Cu" "B.Mask" "B.Paste")
			(roundrect_rratio 0.25)
			(net 2 "GND")
			(pinfunction "GND")
			(pintype "power_in")
		)
		(pad "A4" smd roundrect
			(at -2.4 3.5)
			(size 0.6 1.15)
			(layers "B.Cu" "B.Mask" "B.Paste")
			(roundrect_rratio 0.25)
			(net 6 "VBUS")
			(pinfunction "VBUS")
			(pintype "power_in")
		)
		(pad "A5" smd roundrect
			(at -1.25 3.5)
			(size 0.3 1.15)
			(layers "B.Cu" "B.Mask" "B.Paste")
			(roundrect_rratio 0.25)
			(net 29 "/USB PD/CC1")
			(pinfunction "CC_{1}")
			(pintype "bidirectional")
		)
		(pad "A6" smd roundrect
			(at -0.25 3.5)
			(size 0.3 1.15)
			(layers "B.Cu" "B.Mask" "B.Paste")
			(roundrect_rratio 0.25)
			(net 30 "unconnected-(J1-D_{A}+-PadA6)")
			(pinfunction "D_{A}+")
			(pintype "bidirectional+no_connect")
		)
		(pad "A7" smd roundrect
			(at 0.248 3.5)
			(size 0.3 1.15)
			(layers "B.Cu" "B.Mask" "B.Paste")
			(roundrect_rratio 0.25)
			(net 31 "unconnected-(J1-D_{A}--PadA7)")
			(pinfunction "D_{A}-")
			(pintype "bidirectional+no_connect")
		)
		(pad "A8" smd roundrect
			(at 1.249 3.5)
			(size 0.3 1.15)
			(layers "B.Cu" "B.Mask" "B.Paste")
			(roundrect_rratio 0.25)
			(net 32 "unconnected-(J1-SBU_{1}-PadA8)")
			(pinfunction "SBU_{1}")
			(pintype "bidirectional+no_connect")
		)
		(pad "A9" smd roundrect
			(at 2.398 3.5)
			(size 0.6 1.15)
			(layers "B.Cu" "B.Mask" "B.Paste")
			(roundrect_rratio 0.25)
			(net 6 "VBUS")
			(pinfunction "VBUS")
			(pintype "passive")
		)
		(pad "A12" smd roundrect
			(at 3.2 3.5)
			(size 0.6 1.15)
			(layers "B.Cu" "B.Mask" "B.Paste")
			(roundrect_rratio 0.25)
			(net 2 "GND")
			(pinfunction "GND")
			(pintype "passive")
		)
		(pad "B1" smd roundrect
			(at 3.2 3.5)
			(size 0.6 1.15)
			(layers "B.Cu" "B.Mask" "B.Paste")
			(roundrect_rratio 0.25)
			(net 2 "GND")
			(pinfunction "GND")
			(pintype "passive")
		)
		(pad "B4" smd roundrect
			(at 2.398 3.5)
			(size 0.6 1.15)
			(layers "B.Cu" "B.Mask" "B.Paste")
			(roundrect_rratio 0.25)
			(net 6 "VBUS")
			(pinfunction "VBUS")
			(pintype "passive")
		)
		(pad "B5" smd roundrect
			(at 1.749 3.5)
			(size 0.3 1.15)
			(layers "B.Cu" "B.Mask" "B.Paste")
			(roundrect_rratio 0.25)
			(net 33 "/USB PD/CC2")
			(pinfunction "CC_{2}")
			(pintype "bidirectional")
		)
		(pad "B6" smd roundrect
			(at 0.748 3.5)
			(size 0.3 1.15)
			(layers "B.Cu" "B.Mask" "B.Paste")
			(roundrect_rratio 0.25)
			(net 34 "unconnected-(J1-D_{B}+-PadB6)")
			(pinfunction "D_{B}+")
			(pintype "bidirectional+no_connect")
		)
		(pad "B7" smd roundrect
			(at -0.75 3.5)
			(size 0.3 1.15)
			(layers "B.Cu" "B.Mask" "B.Paste")
			(roundrect_rratio 0.25)
			(net 35 "unconnected-(J1-D_{B}--PadB7)")
			(pinfunction "D_{B}-")
			(pintype "bidirectional+no_connect")
		)
		(pad "B8" smd roundrect
			(at -1.75 3.5)
			(size 0.3 1.15)
			(layers "B.Cu" "B.Mask" "B.Paste")
			(roundrect_rratio 0.25)
			(net 36 "unconnected-(J1-SBU_{2}-PadB8)")
			(pinfunction "SBU_{2}")
			(pintype "bidirectional+no_connect")
		)
		(pad "B9" smd roundrect
			(at -2.4 3.5)
			(size 0.6 1.15)
			(layers "B.Cu" "B.Mask" "B.Paste")
			(roundrect_rratio 0.25)
			(net 6 "VBUS")
			(pinfunction "VBUS")
			(pintype "passive")
		)
		(pad "B12" smd roundrect
			(at -3.202 3.5)
			(size 0.6 1.15)
			(layers "B.Cu" "B.Mask" "B.Paste")
			(roundrect_rratio 0.25)
			(net 2 "GND")
			(pinfunction "GND")
			(pintype "passive")
		)
		(pad "SH" thru_hole oval
			(at -4.321 -1.255)
			(size 1 2)
			(drill oval 0.6 1.4)
			(layers "*.Cu" "*.Mask")
			(remove_unused_layers no)
			(net 2 "GND")
			(pinfunction "SH")
			(pintype "passive")
		)
		(pad "SH" thru_hole oval
			(at -4.321 2.926)
			(size 1.05 2.1)
			(drill oval 0.6 1.7)
			(layers "*.Cu" "*.Mask")
			(remove_unused_layers no)
			(net 2 "GND")
			(pinfunction "SH")
			(pintype "passive")
		)
		(pad "SH" thru_hole oval
			(at 4.32 -1.255)
			(size 1 2)
			(drill oval 0.6 1.4)
			(layers "*.Cu" "*.Mask")
			(remove_unused_layers no)
			(net 2 "GND")
			(pinfunction "SH")
			(pintype "passive")
		)
		(pad "SH" thru_hole oval
			(at 4.32 2.926)
			(size 1.05 2.1)
			(drill oval 0.6 1.7)
			(layers "*.Cu" "*.Mask")
			(remove_unused_layers no)
			(net 2 "GND")
			(pinfunction "SH")
			(pintype "passive")
		)
	)
	(footprint "antmicro-footprints:C_0805_2012Metric"
		(layer "B.Cu")
		(at 101.6 93.75 -90)
		(descr "Capacitor SMD 0805")
		(tags "capacitor SMD 0805")
		(property "Reference" "C30"
			(at -1.0908 -1.6764 90)
			(layer "B.SilkS")
			(effects
				(font
					(size 0.7 0.7)
					(thickness 0.15)
				)
				(justify left bottom mirror)
			)
		)
		(property "Value" "C_22u_25V_0805"
			(at -2.055717 -1.963152 90)
			(layer "B.Fab")
			(effects
				(font
					(size 0.7 0.7)
					(thickness 0.15)
				)
				(justify left bottom mirror)
			)
		)
		(property "Datasheet" "https://product.samsungsem.com/mlcc/CL21A226MAYNNN.do"
			(at 0 0 270)
			(layer "F.Fab")
			(hide yes)
			(effects
				(font
					(size 1.27 1.27)
					(thickness 0.15)
				)
			)
		)
		(property "Description" "SMT Multilayer Ceramic Capacitor, 22uF, +/-20%, 25V, X5R, 0805 [2012 Metric]"
			(at 0 0 270)
			(layer "F.Fab")
			(hide yes)
			(effects
				(font
					(size 1.27 1.27)
					(thickness 0.15)
				)
			)
		)
		(property "MPN" "CL21A226MAYNNNE"
			(at 0 0 270)
			(unlocked yes)
			(layer "B.Fab")
			(hide yes)
			(effects
				(font
					(size 1 1)
					(thickness 0.15)
				)
				(justify mirror)
			)
		)
		(property "Manufacturer" "Samsung Electro-Mechanics"
			(at 0 0 270)
			(unlocked yes)
			(layer "B.Fab")
			(hide yes)
			(effects
				(font
					(size 1 1)
					(thickness 0.15)
				)
				(justify mirror)
			)
		)
		(property "License" "Apache-2.0"
			(at 0 0 270)
			(unlocked yes)
			(layer "B.Fab")
			(hide yes)
			(effects
				(font
					(size 1 1)
					(thickness 0.15)
				)
				(justify mirror)
			)
		)
		(property "Author" "Antmicro"
			(at 0 0 270)
			(unlocked yes)
			(layer "B.Fab")
			(hide yes)
			(effects
				(font
					(size 1 1)
					(thickness 0.15)
				)
				(justify mirror)
			)
		)
		(property "Val" "22u"
			(at 0 0 270)
			(unlocked yes)
			(layer "B.Fab")
			(hide yes)
			(effects
				(font
					(size 1 1)
					(thickness 0.15)
				)
				(justify mirror)
			)
		)
		(property "Voltage" "25V"
			(at 0 0 270)
			(unlocked yes)
			(layer "B.Fab")
			(hide yes)
			(effects
				(font
					(size 1 1)
					(thickness 0.15)
				)
				(justify mirror)
			)
		)
		(property "Dielectric" "X5R"
			(at 0 0 270)
			(unlocked yes)
			(layer "B.Fab")
			(hide yes)
			(effects
				(font
					(size 1 1)
					(thickness 0.15)
				)
				(justify mirror)
			)
		)
		(property "Public" "False"
			(at 0 0 270)
			(unlocked yes)
			(layer "B.Fab")
			(hide yes)
			(effects
				(font
					(size 1 1)
					(thickness 0.15)
				)
				(justify mirror)
			)
		)
		(sheetname "/DC-DC Converters/")
		(sheetfile "dc-dc_converters.kicad_sch")
		(attr smd)
		(fp_line
			(start 0.3 0.7)
			(end -0.3 0.7)
			(stroke
				(width 0.15)
				(type solid)
			)
			(layer "B.SilkS")
		)
		(fp_line
			(start 0.3 -0.7)
			(end -0.3 -0.7)
			(stroke
				(width 0.15)
				(type solid)
			)
			(layer "B.SilkS")
		)
		(fp_rect
			(start 1.95 0.9)
			(end -1.95 -0.9)
			(stroke
				(width 0.05)
				(type default)
			)
			(fill no)
			(layer "B.CrtYd")
		)
		(fp_rect
			(start -0.95 0.675)
			(end 0.95 -0.675)
			(stroke
				(width 0.15)
				(type solid)
			)
			(fill no)
			(layer "B.Fab")
		)
		(pad "1" smd roundrect
			(at -1.1 0 270)
			(size 1.2 1.3)
			(layers "B.Cu" "B.Mask" "B.Paste")
			(roundrect_rratio 0.25)
			(net 2 "GND")
			(pintype "passive")
		)
		(pad "2" smd roundrect
			(at 1.1 0 270)
			(size 1.2 1.3)
			(layers "B.Cu" "B.Mask" "B.Paste")
			(roundrect_rratio 0.25)
			(net 5 "+12V")
			(pintype "passive")
		)
	)
	(footprint "antmicro-footprints:Conn_JST_SH_1x4_SM04B-SRSS-TB-LF-SN"
		(layer "B.Cu")
		(at 100.301 88.1 -90)
		(property "Reference" "J3"
			(at -2.35 2.15 180)
			(layer "B.SilkS")
			(effects
				(font
					(size 0.7 0.7)
					(thickness 0.15)
				)
				(justify left bottom mirror)
			)
		)
		(property "Value" "JST_SH_1x4_SM04B-SRSS-TB-LF-SN"
			(at 0 -3.9 90)
			(layer "B.Fab")
			(effects
				(font
					(size 0.7 0.7)
					(thickness 0.15)
				)
				(justify left bottom mirror)
			)
		)
		(property "Datasheet" "https://www.jst-mfg.com/product/pdf/eng/eSH.pdf"
			(at 0 0 270)
			(layer "F.Fab")
			(hide yes)
			(effects
				(font
					(size 1.27 1.27)
					(thickness 0.15)
				)
			)
		)
		(property "Description" "Pin Header, Right Angle, Wire-to-Board, 1 mm, 1 Rows, 4 Contacts, Surface Mount Right Angle, SH"
			(at 0 0 270)
			(layer "F.Fab")
			(hide yes)
			(effects
				(font
					(size 1.27 1.27)
					(thickness 0.15)
				)
			)
		)
		(property "MPN" "SM04B-SRSS-TB(LF)(SN)"
			(at 0 0 270)
			(unlocked yes)
			(layer "B.Fab")
			(hide yes)
			(effects
				(font
					(size 1 1)
					(thickness 0.15)
				)
				(justify mirror)
			)
		)
		(property "Manufacturer" "JST Automotive Connectors"
			(at 0 0 270)
			(unlocked yes)
			(layer "B.Fab")
			(hide yes)
			(effects
				(font
					(size 1 1)
					(thickness 0.15)
				)
				(justify mirror)
			)
		)
		(property "Author" "Antmicro"
			(at 0 0 270)
			(unlocked yes)
			(layer "B.Fab")
			(hide yes)
			(effects
				(font
					(size 1 1)
					(thickness 0.15)
				)
				(justify mirror)
			)
		)
		(property "License" "Apache-2.0"
			(at 0 0 270)
			(unlocked yes)
			(layer "B.Fab")
			(hide yes)
			(effects
				(font
					(size 1 1)
					(thickness 0.15)
				)
				(justify mirror)
			)
		)
		(sheetname "/DC-DC Converters/")
		(sheetfile "dc-dc_converters.kicad_sch")
		(attr smd)
		(fp_line
			(start -3.2 2)
			(end -2 2)
			(stroke
				(width 0.15)
				(type solid)
			)
			(layer "B.SilkS")
		)
		(fp_line
			(start 3.2 2)
			(end 2 2)
			(stroke
				(width 0.15)
				(type solid)
			)
			(layer "B.SilkS")
		)
		(fp_line
			(start -3.2 -0.6)
			(end -3.2 2)
			(stroke
				(width 0.15)
				(type solid)
			)
			(layer "B.SilkS")
		)
		(fp_line
			(start 3.2 -0.6)
			(end 3.2 2)
			(stroke
				(width 0.15)
				(type solid)
			)
			(layer "B.SilkS")
		)
		(fp_line
			(start 2 -2.6)
			(end -2 -2.6)
			(stroke
				(width 0.15)
				(type solid)
			)
			(layer "B.SilkS")
		)
		(fp_circle
			(center -2.1 2.5)
			(end -2.05 2.5)
			(stroke
				(width 0.15)
				(type solid)
			)
			(fill yes)
			(layer "B.SilkS")
		)
		(fp_rect
			(start -3.65 3.14)
			(end 3.65 -2.9)
			(stroke
				(width 0.05)
				(type solid)
			)
			(fill no)
			(layer "B.CrtYd")
		)
		(fp_rect
			(start -3 2.475)
			(end 3 -2.475)
			(stroke
				(width 0.15)
				(type solid)
			)
			(fill no)
			(layer "B.Fab")
		)
		(pad "1" smd roundrect
			(at -1.5 2.12 90)
			(size 0.6 1.55)
			(layers "B.Cu" "B.Mask" "B.Paste")
			(roundrect_rratio 0.25)
			(net 2 "GND")
			(pintype "passive")
		)
		(pad "2" smd roundrect
			(at -0.5 2.12 90)
			(size 0.6 1.55)
			(layers "B.Cu" "B.Mask" "B.Paste")
			(roundrect_rratio 0.25)
			(net 1 "+3V3")
			(pintype "passive")
		)
		(pad "3" smd roundrect
			(at 0.5 2.12 90)
			(size 0.6 1.55)
			(layers "B.Cu" "B.Mask" "B.Paste")
			(roundrect_rratio 0.25)
			(net 2 "GND")
			(pintype "passive")
		)
		(pad "4" smd roundrect
			(at 1.5 2.12 90)
			(size 0.6 1.55)
			(layers "B.Cu" "B.Mask" "B.Paste")
			(roundrect_rratio 0.25)
			(net 25 "+5V")
			(pintype "passive")
		)
		(pad "MP" smd roundrect
			(at -2.8 -1.755 270)
			(size 1.2 1.8)
			(layers "B.Cu" "B.Mask" "B.Paste")
			(roundrect_rratio 0.25)
			(net 2 "GND")
			(pintype "passive")
		)
		(pad "MP" smd roundrect
			(at 2.8 -1.755 270)
			(size 1.2 1.8)
			(layers "B.Cu" "B.Mask" "B.Paste")
			(roundrect_rratio 0.25)
			(net 2 "GND")
			(pintype "passive")
		)
	)
)
